# T6G (Grand Teton) — schematic netlist excerpt (pin names and nets, part order shuffled) for the footprints in the layout excerpt that follows; sources: Cadence DE-HDL packaged netlist, KiCad conversion of 04192023_DAF0TMB3IC0_F0TG_MB_C_brd_V02_OCP.brd

C865  Q_CAP_DIFFBUS  DIFF BUS_0.22UF 6.3V 20% X6S  pkg C0201  page 64 : \1\ = P5E_CPU0_P2_TX_C_DP<2> ; \2\ = P5E_CPU0_P2_TX_DP<2>
R3833  Q_RES  100K 1% CHIP  pkg 0402LF  page 140 : A = P3V3_AUX ; B = P3V3_OCP_FAULT_2
R1736  Q_RES  0 5% CHIP  pkg 0402LF  page 171 : A = JTAG_SCM_MUX_R_TCK ; B = JTAG_SCM_MUX_TCK

(kicad_pcb
	(version 20260206)
	(generator "pcbnew")
	(generator_version "10.0")
	(general
		(thickness 1.6)
		(legacy_teardrops no)
	)
	(paper "A4")
	(title_block
		(title "04192023_DAF0TMB3IC0_F0TG_MB_C_brd_V02_OCP.brd")
		(comment 1 "Grand Teton / footprints 206-208 of 8354")
	)
	(layers
		(0 "F.Cu" signal "TOP")
		(4 "In1.Cu" signal "GND")
		(6 "In2.Cu" signal "IN1")
		(8 "In3.Cu" signal "GND1")
		(10 "In4.Cu" signal "IN2")
		(12 "In5.Cu" signal "GND2")
		(14 "In6.Cu" signal "IN3")
		(16 "In7.Cu" signal "GND3")
		(18 "In8.Cu" signal "VCC")
		(20 "In9.Cu" signal "VCC1")
		(22 "In10.Cu" signal "GND4")
		(24 "In11.Cu" signal "IN4")
		(26 "In12.Cu" signal "GND5")
		(28 "In13.Cu" signal "IN5")
		(30 "In14.Cu" signal "GND6")
		(32 "In15.Cu" signal "IN6")
		(34 "In16.Cu" signal "GND7")
		(2 "B.Cu" signal "BOTTOM")
		(9 "F.Adhes" user "F.Adhesive")
		(11 "B.Adhes" user "B.Adhesive")
		(13 "F.Paste" user "Package Geometry/Pastemask Top")
		(15 "B.Paste" user "Package Geometry/Pastemask Bottom")
		(5 "F.SilkS" user "Ref Des/Silkscreen Top")
		(7 "B.SilkS" user "Ref Des/Silkscreen Bottom")
		(1 "F.Mask" user "Board Geometry/Soldermask Top")
		(3 "B.Mask" user "Board Geometry/Soldermask Bottom")
		(17 "Dwgs.User" user "User.Drawings")
		(19 "Cmts.User" user "User.Comments")
		(21 "Eco1.User" user "User.Eco1")
		(23 "Eco2.User" user "User.Eco2")
		(25 "Edge.Cuts" user "Board Geometry/Outline")
		(27 "Margin" user)
		(31 "F.CrtYd" user "Package Geometry/Place Bound Top")
		(29 "B.CrtYd" user "Package Geometry/Place Bound Bottom")
		(35 "F.Fab" user "Ref Des/Assembly Top")
		(33 "B.Fab" user "Ref Des/Assembly Bottom")
	)
	(footprint ""
		(layer "F.Cu")
		(at 118.718584 -60.900056)
		(property "Reference" "R1736"
			(at 0 0 0)
			(layer "F.SilkS")
			(hide yes)
			(effects
				(font
					(size 1.27 1.27)
				)
			)
		)
		(property "Value" ""
			(at 0 0 0)
			(layer "F.Fab")
			(effects
				(font
					(size 1.27 1.27)
				)
			)
		)
		(duplicate_pad_numbers_are_jumpers no)
		(fp_line
			(start -0.7874 -0.4064)
			(end 0.7874 -0.4064)
			(stroke
				(width 0.1524)
				(type default)
			)
			(layer "F.SilkS")
		)
		(fp_line
			(start -0.7874 0.4064)
			(end -0.7874 -0.4064)
			(stroke
				(width 0.1524)
				(type default)
			)
			(layer "F.SilkS")
		)
		(fp_line
			(start 0.7874 -0.4064)
			(end 0.7874 0.4064)
			(stroke
				(width 0.1524)
				(type default)
			)
			(layer "F.SilkS")
		)
		(fp_line
			(start 0.7874 0.4064)
			(end -0.7874 0.4064)
			(stroke
				(width 0.1524)
				(type default)
			)
			(layer "F.SilkS")
		)
		(fp_line
			(start -0.67945 -0.305054)
			(end -0.12065 -0.305054)
			(stroke
				(width 0.1)
				(type default)
			)
			(layer "F.Fab")
		)
		(fp_line
			(start -0.67945 0.3048)
			(end -0.67945 -0.305054)
			(stroke
				(width 0.1)
				(type default)
			)
			(layer "F.Fab")
		)
		(fp_line
			(start -0.12065 -0.305054)
			(end -0.12065 -0.2794)
			(stroke
				(width 0.1)
				(type default)
			)
			(layer "F.Fab")
		)
		(fp_line
			(start -0.12065 -0.2794)
			(end 0.12065 -0.2794)
			(stroke
				(width 0.1)
				(type default)
			)
			(layer "F.Fab")
		)
		(fp_line
			(start -0.12065 0.2794)
			(end -0.12065 0.3048)
			(stroke
				(width 0.1)
				(type default)
			)
			(layer "F.Fab")
		)
		(fp_line
			(start -0.12065 0.3048)
			(end -0.67945 0.3048)
			(stroke
				(width 0.1)
				(type default)
			)
			(layer "F.Fab")
		)
		(fp_line
			(start 0.120396 0.2794)
			(end -0.12065 0.2794)
			(stroke
				(width 0.1)
				(type default)
			)
			(layer "F.Fab")
		)
		(fp_line
			(start 0.120396 0.3048)
			(end 0.120396 0.2794)
			(stroke
				(width 0.1)
				(type default)
			)
			(layer "F.Fab")
		)
		(fp_line
			(start 0.12065 -0.3048)
			(end 0.67945 -0.3048)
			(stroke
				(width 0.1)
				(type default)
			)
			(layer "F.Fab")
		)
		(fp_line
			(start 0.12065 -0.2794)
			(end 0.12065 -0.3048)
			(stroke
				(width 0.1)
				(type default)
			)
			(layer "F.Fab")
		)
		(fp_line
			(start 0.67945 -0.3048)
			(end 0.67945 0.3048)
			(stroke
				(width 0.1)
				(type default)
			)
			(layer "F.Fab")
		)
		(fp_line
			(start 0.67945 0.3048)
			(end 0.120396 0.3048)
			(stroke
				(width 0.1)
				(type default)
			)
			(layer "F.Fab")
		)
		(pad "1" smd circle
			(at -0.40005 0)
			(size 0 0)
			(layers "F.Cu" "F.Mask" "F.Paste")
			(net "JTAG_SCM_MUX_R_TCK")
		)
		(pad "2" smd circle
			(at 0.40005 0)
			(size 0 0)
			(layers "F.Cu" "F.Mask" "F.Paste")
			(net "JTAG_SCM_MUX_TCK")
		)
	)
	(footprint ""
		(layer "F.Cu")
		(at 398.61744 -381.41783 -90)
		(property "Reference" "C865"
			(at 0 0 270)
			(layer "F.SilkS")
			(hide yes)
			(effects
				(font
					(size 1.27 1.27)
				)
			)
		)
		(property "Value" ""
			(at 0 0 270)
			(layer "F.Fab")
			(effects
				(font
					(size 1.27 1.27)
				)
			)
		)
		(duplicate_pad_numbers_are_jumpers no)
		(fp_line
			(start -0.299974 0.150114)
			(end -0.299974 -0.150114)
			(stroke
				(width 0.1)
				(type default)
			)
			(layer "F.Fab")
		)
		(fp_line
			(start 0.299974 0.150114)
			(end -0.299974 0.150114)
			(stroke
				(width 0.1)
				(type default)
			)
			(layer "F.Fab")
		)
		(fp_line
			(start -0.299974 -0.150114)
			(end 0.299974 -0.150114)
			(stroke
				(width 0.1)
				(type default)
			)
			(layer "F.Fab")
		)
		(fp_line
			(start 0.299974 -0.150114)
			(end 0.299974 0.150114)
			(stroke
				(width 0.1)
				(type default)
			)
			(layer "F.Fab")
		)
		(pad "1" smd rect
			(at -0.2667 0 270)
			(size 0.3048 0.381)
			(layers "F.Cu" "F.Mask" "F.Paste")
			(net "P5E_CPU0_P2_TX_C_DP<2>")
		)
		(pad "2" smd rect
			(at 0.2667 0 270)
			(size 0.3048 0.381)
			(layers "F.Cu" "F.Mask" "F.Paste")
			(net "P5E_CPU0_P2_TX_DP<2>")
		)
	)
	(footprint ""
		(layer "F.Cu")
		(at 87.557864 -57.16778)
		(property "Reference" "R3833"
			(at 0 0 0)
			(layer "F.SilkS")
			(hide yes)
			(effects
				(font
					(size 1.27 1.27)
				)
			)
		)
		(property "Value" ""
			(at 0 0 0)
			(layer "F.Fab")
			(effects
				(font
					(size 1.27 1.27)
				)
			)
		)
		(duplicate_pad_numbers_are_jumpers no)
		(fp_line
			(start -0.7874 -0.4064)
			(end 0.7874 -0.4064)
			(stroke
				(width 0.1524)
				(type default)
			)
			(layer "F.SilkS")
		)
		(fp_line
			(start -0.7874 0.4064)
			(end -0.7874 -0.4064)
			(stroke
				(width 0.1524)
				(type default)
			)
			(layer "F.SilkS")
		)
		(fp_line
			(start 0.7874 -0.4064)
			(end 0.7874 0.4064)
			(stroke
				(width 0.1524)
				(type default)
			)
			(layer "F.SilkS")
		)
		(fp_line
			(start 0.7874 0.4064)
			(end -0.7874 0.4064)
			(stroke
				(width 0.1524)
				(type default)
			)
			(layer "F.SilkS")
		)
		(fp_line
			(start -0.67945 -0.305054)
			(end -0.12065 -0.305054)
			(stroke
				(width 0.1)
				(type default)
			)
			(layer "F.Fab")
		)
		(fp_line
			(start -0.67945 0.3048)
			(end -0.67945 -0.305054)
			(stroke
				(width 0.1)
				(type default)
			)
			(layer "F.Fab")
		)
		(fp_line
			(start -0.12065 -0.305054)
			(end -0.12065 -0.2794)
			(stroke
				(width 0.1)
				(type default)
			)
			(layer "F.Fab")
		)
		(fp_line
			(start -0.12065 -0.2794)
			(end 0.12065 -0.2794)
			(stroke
				(width 0.1)
				(type default)
			)
			(layer "F.Fab")
		)
		(fp_line
			(start -0.12065 0.2794)
			(end -0.12065 0.3048)
			(stroke
				(width 0.1)
				(type default)
			)
			(layer "F.Fab")
		)
		(fp_line
			(start -0.12065 0.3048)
			(end -0.67945 0.3048)
			(stroke
				(width 0.1)
				(type default)
			)
			(layer "F.Fab")
		)
		(fp_line
			(start 0.120396 0.2794)
			(end -0.12065 0.2794)
			(stroke
				(width 0.1)
				(type default)
			)
			(layer "F.Fab")
		)
		(fp_line
			(start 0.120396 0.3048)
			(end 0.120396 0.2794)
			(stroke
				(width 0.1)
				(type default)
			)
			(layer "F.Fab")
		)
		(fp_line
			(start 0.12065 -0.3048)
			(end 0.67945 -0.3048)
			(stroke
				(width 0.1)
				(type default)
			)
			(layer "F.Fab")
		)
		(fp_line
			(start 0.12065 -0.2794)
			(end 0.12065 -0.3048)
			(stroke
				(width 0.1)
				(type default)
			)
			(layer "F.Fab")
		)
		(fp_line
			(start 0.67945 -0.3048)
			(end 0.67945 0.3048)
			(stroke
				(width 0.1)
				(type default)
			)
			(layer "F.Fab")
		)
		(fp_line
			(start 0.67945 0.3048)
			(end 0.120396 0.3048)
			(stroke
				(width 0.1)
				(type default)
			)
			(layer "F.Fab")
		)
		(pad "1" smd circle
			(at -0.40005 0)
			(size 0 0)
			(layers "F.Cu" "F.Mask" "F.Paste")
			(net "P3V3_AUX")
		)
		(pad "2" smd circle
			(at 0.40005 0)
			(size 0 0)
			(layers "F.Cu" "F.Mask" "F.Paste")
			(net "P3V3_OCP_FAULT_2")
		)
	)
)
